FILE_TYPE = CONNECTIVITY;
{Allegro Design Entry HDL 17.4-2019 S026 (4007227) 1/17/2022}
"PAGE_NUMBER" = 454;
0"NC";
1"P0V9_CPU1_RT2_2A\g";
2"GND\g";
3"P0V9_CPU1_RT_2D\g";
4"GND\g";
5"P1V8_CPU1_RT2_1A\g";
6"GND\g";
7"P1V8_CPU1_RT_1D\g";
8"GND\g";
9"P0V9_CPU1_RT2_2A_2D\g";
10"GND\g";
11"GND\g";
12"GND\g";
13"P1V8_CPU1_RT2_1A_1D\g";
%"Q_CAP"
"1","(-6925,4325)","0","pure_quanta","I10";
;
LOCATION"C369"
$SEC"1"
CDS_SEC"1"
MATERIAL"X6S"
VOLTAGE"4V"
TOLERANCE"20%"
PACK_TYPE"C0402"
VALUE"22UF"
CDS_LIB"pure_quanta"
PART_NUMBER"CH622KMEB02";
"B"
$PN"2"6;
"A"
$PN"1"5;
%"Q_CAP"
"1","(-425,2400)","0","pure_quanta","I100";
;
LOCATION"C7028"
$SEC"1"
CDS_SEC"1"
VOLTAGE"4V"
VALUE"100UF"
PACK_TYPE"C0805"
MATERIAL"X6S"
TOLERANCE"20%"
CDS_LIB"pure_quanta"
PART_NUMBER"CH710KMEA01";
"B"
$PN"2"11;
"A"
$PN"1"1;
%"Q_CAPP"
"1","(-1575,5000)","0","pure_quanta","I101";
;
LOCATION"C7037"
$SEC"1"
CDS_SEC"1"
PACK_TYPE"SMLF"
MATERIAL"SPCAP"
VALUE"470UF"
TOLERANCE"20%"
VOLTAGE"2.5V"
CDS_LIB"pure_quanta"
PART_NUMBER"CH747LM8818";
"A"
$PN"1"3;
"B"
$PN"2"4;
%"Q_CAP"
"1","(-1275,5000)","0","pure_quanta","I102";
;
LOCATION"C7038"
$SEC"1"
CDS_SEC"1"
PACK_TYPE"C0805"
MATERIAL"X6S"
VALUE"47UF"
VOLTAGE"4V"
TOLERANCE"20%"
CDS_LIB"pure_quanta"
PART_NUMBER"CH647KMEA04";
"B"
$PN"2"4;
"A"
$PN"1"3;
%"Q_CAP"
"1","(-1025,5000)","0","pure_quanta","I103";
;
LOCATION"C7039"
$SEC"1"
CDS_SEC"1"
MATERIAL"X6S"
PACK_TYPE"C0805"
VOLTAGE"4V"
VALUE"47UF"
TOLERANCE"20%"
CDS_LIB"pure_quanta"
PART_NUMBER"CH647KMEA04";
"B"
$PN"2"4;
"A"
$PN"1"3;
%"Q_CAP"
"1","(-800,5000)","0","pure_quanta","I104";
;
LOCATION"C7040"
$SEC"1"
CDS_SEC"1"
MATERIAL"X6S"
PACK_TYPE"C0805"
TOLERANCE"20%"
VALUE"47UF"
VOLTAGE"4V"
CDS_LIB"pure_quanta"
PART_NUMBER"CH647KMEA04";
"B"
$PN"2"4;
"A"
$PN"1"3;
%"Q_CAP"
"1","(-550,5000)","0","pure_quanta","I105";
;
LOCATION"C7041"
$SEC"1"
CDS_SEC"1"
VALUE"47UF"
MATERIAL"X6S"
PACK_TYPE"C0805"
TOLERANCE"20%"
VOLTAGE"4V"
CDS_LIB"pure_quanta"
PART_NUMBER"CH647KMEA04";
"B"
$PN"2"4;
"A"
$PN"1"3;
%"Q_CAP"
"1","(-6725,4325)","0","pure_quanta","I11";
;
LOCATION"C372"
$SEC"1"
CDS_SEC"1"
TOLERANCE"20%"
VOLTAGE"6.3V"
VALUE"10UF"
MATERIAL"X6S"
PACK_TYPE"C0402"
CDS_LIB"pure_quanta"
PART_NUMBER"CH6101MEB01";
"B"
$PN"2"6;
"A"
$PN"1"5;
%"Q_CAP"
"1","(-6525,4325)","0","pure_quanta","I12";
;
LOCATION"C371"
$SEC"1"
CDS_SEC"1"
VALUE"4.7UF"
VOLTAGE"6.3V"
TOLERANCE"20%"
MATERIAL"X6S"
PACK_TYPE"0402"
CDS_LIB"pure_quanta"
PART_NUMBER"CH5471MEB01";
"B"
$PN"2"6;
"A"
$PN"1"5;
%"Q_CAP"
"1","(-6300,4325)","0","pure_quanta","I13";
;
LOCATION"C374"
$SEC"1"
CDS_SEC"1"
TOLERANCE"20%"
VOLTAGE"4V"
VALUE"1UF"
MATERIAL"X6S"
PACK_TYPE"0201"
CDS_LIB"pure_quanta"
PART_NUMBER"CH-10KMEE00";
"B"
$PN"2"6;
"A"
$PN"1"5;
%"UNIVERSAL_GND"
"1","(-6100,4000)","0","pure_quanta_power","I14";
;
CDS_LIB"pure_quanta_power"
HDL_POWER"GND";
"A"6;
%"Q_CAP"
"1","(-6100,4325)","0","pure_quanta","I15";
;
LOCATION"C376"
$SEC"1"
CDS_SEC"1"
PACK_TYPE"0201"
MATERIAL"X6S"
TOLERANCE"20%"
VALUE"1UF"
VOLTAGE"4V"
CDS_LIB"pure_quanta"
PART_NUMBER"CH-10KMEE00";
"B"
$PN"2"6;
"A"
$PN"1"5;
%"Q_CAP"
"1","(-5875,4325)","0","pure_quanta","I16";
;
LOCATION"C377"
$SEC"1"
CDS_SEC"1"
VALUE"0.1UF"
VOLTAGE"10V"
TOLERANCE"10%"
MATERIAL"X7S"
PACK_TYPE"C0201"
CDS_LIB"pure_quanta"
PART_NUMBER"CH4102K6E00";
"B"
$PN"2"6;
"A"
$PN"1"5;
%"Q_CAP"
"1","(-5625,4325)","0","pure_quanta","I17";
;
LOCATION"C379"
$SEC"1"
CDS_SEC"1"
TOLERANCE"10%"
VOLTAGE"10V"
VALUE"0.1UF"
MATERIAL"X7S"
PACK_TYPE"C0201"
CDS_LIB"pure_quanta"
PART_NUMBER"CH4102K6E00";
"B"
$PN"2"6;
"A"
$PN"1"5;
%"Q_CAP"
"1","(-5375,4325)","0","pure_quanta","I18";
;
LOCATION"C380"
$SEC"1"
CDS_SEC"1"
VALUE"0.1UF"
TOLERANCE"10%"
MATERIAL"X7S"
PACK_TYPE"C0201"
VOLTAGE"10V"
CDS_LIB"pure_quanta"
PART_NUMBER"CH4102K6E00";
"B"
$PN"2"6;
"A"
$PN"1"5;
%"Q_CAP"
"1","(-5100,4325)","0","pure_quanta","I19";
;
LOCATION"C381"
$SEC"1"
CDS_SEC"1"
VALUE"0.1UF"
TOLERANCE"10%"
MATERIAL"X7S"
PACK_TYPE"C0201"
VOLTAGE"10V"
CDS_LIB"pure_quanta"
PART_NUMBER"CH4102K6E00";
"B"
$PN"2"6;
"A"
$PN"1"5;
%"Q_RES"
"1","(-7650,3900)","0","pure_quanta","I2";
;
LOCATION"R852"
SEC"1"
TOLERANCE"5%"
PACK_TYPE"0402LF"
VALUE"0"
MATERIAL"EMPTY"
WATTAGE"1/16W"
CDS_LIB"pure_quanta"
SEC_TYPE"0402LF"
PART_NUMBER"CS00002JB13";
"B"
$PN"2"5;
"A"
$PN"1"13;
%"Q_RES"
"2","(-4250,2900)","2","pure_quanta","I20";
;
LOCATION"R858"
$SEC"1"
CDS_SEC"1"
TOLERANCE"5%"
VALUE"0"
WATTAGE"1/4W"
MATERIAL"EMPTY"
PACK_TYPE"0603LF"
CDS_LIB"pure_quanta"
PART_NUMBER"CS00006J900";
"A"
$PN"1"3;
"B"
$PN"2"9;
%"Q_INDUCTOR"
"1","(-7725,4600)","0","pure_quanta","I21";
;
LOCATION"L7"
$SEC"1"
CDS_SEC"1"
PACK_TYPE"SMLF"
MATERIAL"IND"
VALUE"BLM21SN300SN1D/5A"
NEEDS_NO_SIZE"TRUE"
CDS_LIB"pure_quanta"
PART_NUMBER"CX300SN1000";
"1"
$PN"1"7;
"2"
$PN"2"5;
%"P1V0"
"1","(-8100,5425)","0","pure_quanta_power","I22";
;
HDL_POWER"P1V8_CPU1_RT_1D"
CDS_LIB"pure_quanta_power";
"A"7;
%"P1V0"
"1","(-7250,4800)","0","pure_quanta_power","I23";
;
HDL_POWER"P1V8_CPU1_RT2_1A"
CDS_LIB"pure_quanta_power";
"A"5;
%"Q_CAP"
"1","(-7000,5150)","0","pure_quanta","I24";
;
LOCATION"C366"
$SEC"1"
CDS_SEC"1"
MATERIAL"X6S"
PACK_TYPE"C0805"
VOLTAGE"4V"
VALUE"100UF"
TOLERANCE"20%"
CDS_LIB"pure_quanta"
PART_NUMBER"CH710KMEA01";
"B"
$PN"2"8;
"A"
$PN"1"7;
%"Q_CAP"
"1","(-6750,5150)","0","pure_quanta","I25";
;
LOCATION"C368"
$SEC"1"
CDS_SEC"1"
PACK_TYPE"C0402"
VOLTAGE"4V"
MATERIAL"X6S"
TOLERANCE"20%"
VALUE"22UF"
CDS_LIB"pure_quanta"
PART_NUMBER"CH622KMEB02";
"B"
$PN"2"8;
"A"
$PN"1"7;
%"UNIVERSAL_GND"
"1","(-6325,4850)","0","pure_quanta_power","I26";
;
CDS_LIB"pure_quanta_power"
HDL_POWER"GND";
"A"8;
%"Q_CAP"
"1","(-6500,5125)","0","pure_quanta","I27";
;
LOCATION"C370"
$SEC"1"
CDS_SEC"1"
VALUE"10UF"
MATERIAL"X6S"
PACK_TYPE"C0402"
TOLERANCE"20%"
VOLTAGE"6.3V"
CDS_LIB"pure_quanta"
PART_NUMBER"CH6101MEB01";
"B"
$PN"2"8;
"A"
$PN"1"7;
%"Q_CAP"
"1","(-6250,5125)","0","pure_quanta","I28";
;
LOCATION"C373"
$SEC"1"
CDS_SEC"1"
VOLTAGE"6.3V"
MATERIAL"X6S"
PACK_TYPE"0402"
TOLERANCE"20%"
VALUE"4.7UF"
CDS_LIB"pure_quanta"
PART_NUMBER"CH5471MEB01";
"B"
$PN"2"8;
"A"
$PN"1"7;
%"VCC_CORE"
"1","(-4250,6100)","0","pure_quanta_power","I29";
;
HDL_POWER"P0V9_CPU1_RT_2D"
CDS_LIB"pure_quanta_power";
"A"3;
%"Q_RES"
"1","(-7650,3700)","0","pure_quanta","I3";
;
LOCATION"R853"
SEC"1"
PACK_TYPE"0402LF"
TOLERANCE"5%"
WATTAGE"1/16W"
MATERIAL"EMPTY"
VALUE"0"
SEC_TYPE"0402LF"
CDS_LIB"pure_quanta"
PART_NUMBER"CS00002JB13";
"B"
$PN"2"5;
"A"
$PN"1"13;
%"VCC_CORE"
"1","(-3100,1800)","0","pure_quanta_power","I30";
;
HDL_POWER"P0V9_CPU1_RT2_2A_2D"
CDS_LIB"pure_quanta_power";
"A"9;
%"Q_CAP"
"1","(-3150,2375)","0","pure_quanta","I31";
;
LOCATION"C421"
$SEC"1"
CDS_SEC"1"
VALUE"0.1UF"
VOLTAGE"10V"
TOLERANCE"10%"
MATERIAL"X7S"
PACK_TYPE"C0201"
CDS_LIB"pure_quanta"
PART_NUMBER"CH4102K6E00";
"B"
$PN"2"11;
"A"
$PN"1"1;
%"UNIVERSAL_GND"
"1","(-2275,950)","0","pure_quanta_power","I34";
;
CDS_LIB"pure_quanta_power"
HDL_POWER"GND";
"A"10;
%"Q_CAP"
"1","(-2425,1275)","0","pure_quanta","I35";
;
LOCATION"C396"
$SEC"1"
CDS_SEC"1"
TOLERANCE"10%"
VOLTAGE"10V"
MATERIAL"X7S"
PACK_TYPE"C0201"
VALUE"0.1UF"
CDS_LIB"pure_quanta"
PART_NUMBER"CH4102K6E00";
"B"
$PN"2"10;
"A"
$PN"1"9;
%"Q_CAP"
"1","(-2175,1275)","0","pure_quanta","I36";
;
LOCATION"C397"
$SEC"1"
CDS_SEC"1"
TOLERANCE"10%"
VOLTAGE"10V"
MATERIAL"X7S"
VALUE"0.1UF"
PACK_TYPE"C0201"
CDS_LIB"pure_quanta"
PART_NUMBER"CH4102K6E00";
"B"
$PN"2"10;
"A"
$PN"1"9;
%"Q_CAP"
"1","(-2850,2375)","0","pure_quanta","I37";
;
LOCATION"C427"
$SEC"1"
CDS_SEC"1"
VALUE"0.1UF"
PACK_TYPE"C0201"
MATERIAL"X7S"
TOLERANCE"10%"
VOLTAGE"10V"
CDS_LIB"pure_quanta"
PART_NUMBER"CH4102K6E00";
"B"
$PN"2"11;
"A"
$PN"1"1;
%"Q_CAP"
"1","(-2625,2375)","0","pure_quanta","I38";
;
LOCATION"C393"
$SEC"1"
CDS_SEC"1"
VALUE"0.1UF"
VOLTAGE"10V"
TOLERANCE"10%"
MATERIAL"X7S"
PACK_TYPE"C0201"
CDS_LIB"pure_quanta"
PART_NUMBER"CH4102K6E00";
"B"
$PN"2"11;
"A"
$PN"1"1;
%"Q_CAP"
"1","(-2375,2375)","0","pure_quanta","I39";
;
LOCATION"C430"
$SEC"1"
CDS_SEC"1"
VOLTAGE"10V"
MATERIAL"X7S"
PACK_TYPE"C0201"
TOLERANCE"10%"
VALUE"0.1UF"
CDS_LIB"pure_quanta"
PART_NUMBER"CH4102K6E00";
"B"
$PN"2"11;
"A"
$PN"1"1;
%"Q_CAP"
"1","(-2125,2375)","0","pure_quanta","I40";
;
LOCATION"C400"
$SEC"1"
CDS_SEC"1"
PACK_TYPE"C0201"
VOLTAGE"10V"
TOLERANCE"10%"
MATERIAL"X7S"
VALUE"0.1UF"
CDS_LIB"pure_quanta"
PART_NUMBER"CH4102K6E00";
"B"
$PN"2"11;
"A"
$PN"1"1;
%"Q_RES"
"1","(-3875,2625)","0","pure_quanta","I41";
;
LOCATION"R859"
$SEC"1"
CDS_SEC"1"
MATERIAL"CHIP"
PACK_TYPE"0603LF"
TOLERANCE"5%"
WATTAGE"1/4W"
VALUE"0"
CDS_LIB"pure_quanta"
PART_NUMBER"CS00006J900";
"B"
$PN"2"1;
"A"
$PN"1"9;
%"Q_CAP"
"1","(-3425,3075)","0","pure_quanta","I42";
;
LOCATION"C384"
$SEC"1"
CDS_SEC"1"
MATERIAL"X6S"
PACK_TYPE"0201"
TOLERANCE"20%"
VOLTAGE"4V"
VALUE"1UF"
CDS_LIB"pure_quanta"
PART_NUMBER"CH-10KMEE00";
"B"
$PN"2"2;
"A"
$PN"1"1;
%"Q_CAP"
"1","(-3200,3075)","0","pure_quanta","I43";
;
LOCATION"C387"
$SEC"1"
CDS_SEC"1"
VOLTAGE"4V"
TOLERANCE"20%"
MATERIAL"X6S"
VALUE"1UF"
PACK_TYPE"0201"
CDS_LIB"pure_quanta"
PART_NUMBER"CH-10KMEE00";
"B"
$PN"2"2;
"A"
$PN"1"1;
%"Q_CAP"
"1","(-3425,3700)","0","pure_quanta","I44";
;
LOCATION"C410"
$SEC"1"
CDS_SEC"1"
PACK_TYPE"C0402"
MATERIAL"X6S"
VALUE"10UF"
TOLERANCE"20%"
VOLTAGE"6.3V"
CDS_LIB"pure_quanta"
PART_NUMBER"CH6101MEB01";
"B"
$PN"2"2;
"A"
$PN"1"1;
%"Q_CAP"
"1","(-3200,3700)","0","pure_quanta","I45";
;
LOCATION"C420"
$SEC"1"
CDS_SEC"1"
PACK_TYPE"C0402"
VOLTAGE"6.3V"
VALUE"10UF"
TOLERANCE"20%"
MATERIAL"X6S"
CDS_LIB"pure_quanta"
PART_NUMBER"CH6101MEB01";
"B"
$PN"2"2;
"A"
$PN"1"1;
%"Q_CAP"
"1","(-3425,4325)","0","pure_quanta","I46";
;
LOCATION"C398"
$SEC"1"
CDS_SEC"1"
PACK_TYPE"C0805"
VALUE"100UF"
TOLERANCE"20%"
MATERIAL"X6S"
VOLTAGE"4V"
CDS_LIB"pure_quanta"
PART_NUMBER"CH710KMEA01";
"B"
$PN"2"2;
"A"
$PN"1"1;
%"Q_CAP"
"1","(-3200,4325)","0","pure_quanta","I47";
;
LOCATION"C401"
$SEC"1"
CDS_SEC"1"
MATERIAL"X6S"
PACK_TYPE"C0805"
VOLTAGE"4V"
VALUE"100UF"
TOLERANCE"20%"
CDS_LIB"pure_quanta"
PART_NUMBER"CH710KMEA01";
"B"
$PN"2"2;
"A"
$PN"1"1;
%"Q_CAP"
"1","(-2975,3700)","0","pure_quanta","I48";
;
LOCATION"C406"
$SEC"1"
CDS_SEC"1"
MATERIAL"X6S"
PACK_TYPE"0402"
VALUE"4.7UF"
TOLERANCE"20%"
VOLTAGE"6.3V"
CDS_LIB"pure_quanta"
PART_NUMBER"CH5471MEB01";
"B"
$PN"2"2;
"A"
$PN"1"1;
%"Q_CAP"
"1","(-2950,3075)","0","pure_quanta","I49";
;
LOCATION"C407"
$SEC"1"
CDS_SEC"1"
TOLERANCE"20%"
VOLTAGE"4V"
VALUE"1UF"
PACK_TYPE"0201"
MATERIAL"X6S"
CDS_LIB"pure_quanta"
PART_NUMBER"CH-10KMEE00";
"B"
$PN"2"2;
"A"
$PN"1"1;
%"Q_CAP"
"1","(-7150,4325)","0","pure_quanta","I5";
;
LOCATION"C367"
$SEC"1"
CDS_SEC"1"
PACK_TYPE"C0805"
VOLTAGE"4V"
TOLERANCE"20%"
MATERIAL"X6S"
VALUE"100UF"
CDS_LIB"pure_quanta"
PART_NUMBER"CH710KMEA01";
"B"
$PN"2"6;
"A"
$PN"1"5;
%"Q_CAP"
"1","(-2725,3075)","0","pure_quanta","I50";
;
LOCATION"C391"
$SEC"1"
CDS_SEC"1"
PACK_TYPE"0201"
VOLTAGE"4V"
TOLERANCE"20%"
MATERIAL"X6S"
VALUE"1UF"
CDS_LIB"pure_quanta"
PART_NUMBER"CH-10KMEE00";
"B"
$PN"2"2;
"A"
$PN"1"1;
%"Q_CAP"
"1","(-2475,3075)","0","pure_quanta","I51";
;
LOCATION"C415"
$SEC"1"
CDS_SEC"1"
PACK_TYPE"0201"
VOLTAGE"4V"
TOLERANCE"20%"
MATERIAL"X6S"
VALUE"1UF"
CDS_LIB"pure_quanta"
PART_NUMBER"CH-10KMEE00";
"B"
$PN"2"2;
"A"
$PN"1"1;
%"Q_CAP"
"1","(-2250,3050)","0","pure_quanta","I52";
;
LOCATION"C418"
$SEC"1"
CDS_SEC"1"
PACK_TYPE"0201"
MATERIAL"X6S"
VOLTAGE"4V"
TOLERANCE"20%"
VALUE"1UF"
CDS_LIB"pure_quanta"
PART_NUMBER"CH-10KMEE00";
"B"
$PN"2"2;
"A"
$PN"1"1;
%"Q_CAP"
"1","(-2025,3050)","0","pure_quanta","I53";
;
LOCATION"C422"
$SEC"1"
CDS_SEC"1"
VALUE"1UF"
TOLERANCE"20%"
MATERIAL"X6S"
VOLTAGE"4V"
PACK_TYPE"0201"
CDS_LIB"pure_quanta"
PART_NUMBER"CH-10KMEE00";
"B"
$PN"2"2;
"A"
$PN"1"1;
%"Q_CAP"
"1","(-2750,3700)","0","pure_quanta","I54";
;
LOCATION"C416"
$SEC"1"
CDS_SEC"1"
VALUE"4.7UF"
PACK_TYPE"0402"
VOLTAGE"6.3V"
TOLERANCE"20%"
MATERIAL"X6S"
CDS_LIB"pure_quanta"
PART_NUMBER"CH5471MEB01";
"B"
$PN"2"2;
"A"
$PN"1"1;
%"Q_CAP"
"1","(-2500,3700)","0","pure_quanta","I55";
;
LOCATION"C413"
$SEC"1"
CDS_SEC"1"
PACK_TYPE"0402"
VOLTAGE"6.3V"
VALUE"4.7UF"
TOLERANCE"20%"
MATERIAL"X6S"
CDS_LIB"pure_quanta"
PART_NUMBER"CH5471MEB01";
"B"
$PN"2"2;
"A"
$PN"1"1;
%"Q_CAP"
"1","(-2500,4325)","0","pure_quanta","I56";
;
LOCATION"C417"
$SEC"1"
CDS_SEC"1"
PACK_TYPE"C0402"
MATERIAL"X6S"
TOLERANCE"20%"
VOLTAGE"4V"
VALUE"22UF"
CDS_LIB"pure_quanta"
PART_NUMBER"CH622KMEB02";
"B"
$PN"2"2;
"A"
$PN"1"1;
%"Q_CAP"
"1","(-2275,3700)","0","pure_quanta","I57";
;
LOCATION"C412"
$SEC"1"
CDS_SEC"1"
VALUE"4.7UF"
PACK_TYPE"0402"
MATERIAL"X6S"
TOLERANCE"20%"
VOLTAGE"6.3V"
CDS_LIB"pure_quanta"
PART_NUMBER"CH5471MEB01";
"B"
$PN"2"2;
"A"
$PN"1"1;
%"Q_CAP"
"1","(-2050,3700)","0","pure_quanta","I58";
;
LOCATION"C386"
$SEC"1"
CDS_SEC"1"
TOLERANCE"20%"
PACK_TYPE"0201"
VOLTAGE"4V"
VALUE"1UF"
MATERIAL"X6S"
CDS_LIB"pure_quanta"
PART_NUMBER"CH-10KMEE00";
"B"
$PN"2"2;
"A"
$PN"1"1;
%"Q_CAP"
"1","(-2275,4325)","0","pure_quanta","I59";
;
LOCATION"C399"
$SEC"1"
CDS_SEC"1"
VALUE"22UF"
TOLERANCE"20%"
MATERIAL"X6S"
PACK_TYPE"C0402"
VOLTAGE"4V"
CDS_LIB"pure_quanta"
PART_NUMBER"CH622KMEB02";
"B"
$PN"2"2;
"A"
$PN"1"1;
%"Q_CAP"
"1","(-6725,3250)","0","pure_quanta","I6";
;
LOCATION"C375"
$SEC"1"
CDS_SEC"1"
PACK_TYPE"0201"
MATERIAL"X6S"
VOLTAGE"4V"
TOLERANCE"20%"
VALUE"1UF"
CDS_LIB"pure_quanta"
PART_NUMBER"CH-10KMEE00";
"B"
$PN"2"12;
"A"
$PN"1"13;
%"Q_CAP"
"1","(-2050,4325)","0","pure_quanta","I60";
;
LOCATION"C402"
$SEC"1"
CDS_SEC"1"
PACK_TYPE"C0402"
TOLERANCE"20%"
MATERIAL"X6S"
VALUE"22UF"
VOLTAGE"4V"
CDS_LIB"pure_quanta"
PART_NUMBER"CH622KMEB02";
"B"
$PN"2"2;
"A"
$PN"1"1;
%"Q_CAP"
"1","(-1850,2375)","0","pure_quanta","I61";
;
LOCATION"C403"
$SEC"1"
CDS_SEC"1"
VOLTAGE"10V"
VALUE"0.1UF"
TOLERANCE"10%"
MATERIAL"X7S"
PACK_TYPE"C0201"
CDS_LIB"pure_quanta"
PART_NUMBER"CH4102K6E00";
"B"
$PN"2"11;
"A"
$PN"1"1;
%"Q_CAP"
"1","(-1575,2375)","0","pure_quanta","I62";
;
LOCATION"C411"
$SEC"1"
CDS_SEC"1"
VOLTAGE"10V"
VALUE"0.1UF"
TOLERANCE"10%"
MATERIAL"X7S"
PACK_TYPE"C0201"
CDS_LIB"pure_quanta"
PART_NUMBER"CH4102K6E00";
"B"
$PN"2"11;
"A"
$PN"1"1;
%"UNIVERSAL_GND"
"1","(-1325,1950)","0","pure_quanta_power","I63";
;
CDS_LIB"pure_quanta_power"
HDL_POWER"GND";
"A"11;
%"Q_CAP"
"1","(-1325,2375)","0","pure_quanta","I64";
;
LOCATION"C395"
$SEC"1"
CDS_SEC"1"
PACK_TYPE"C0201"
VOLTAGE"10V"
VALUE"0.1UF"
TOLERANCE"10%"
MATERIAL"X7S"
CDS_LIB"pure_quanta"
PART_NUMBER"CH4102K6E00";
"B"
$PN"2"11;
"A"
$PN"1"1;
%"Q_CAP"
"1","(-1825,3700)","0","pure_quanta","I67";
;
LOCATION"C425"
$SEC"1"
CDS_SEC"1"
MATERIAL"X6S"
PACK_TYPE"0201"
TOLERANCE"20%"
VOLTAGE"4V"
VALUE"1UF"
CDS_LIB"pure_quanta"
PART_NUMBER"CH-10KMEE00";
"B"
$PN"2"2;
"A"
$PN"1"1;
%"Q_CAP"
"1","(-1600,3700)","0","pure_quanta","I68";
;
LOCATION"C389"
$SEC"1"
CDS_SEC"1"
PACK_TYPE"0201"
TOLERANCE"20%"
VOLTAGE"4V"
VALUE"1UF"
MATERIAL"X6S"
CDS_LIB"pure_quanta"
PART_NUMBER"CH-10KMEE00";
"B"
$PN"2"2;
"A"
$PN"1"1;
%"Q_CAP"
"1","(-1825,4325)","0","pure_quanta","I69";
;
LOCATION"C424"
$SEC"1"
CDS_SEC"1"
MATERIAL"X6S"
TOLERANCE"20%"
VALUE"22UF"
PACK_TYPE"C0402"
VOLTAGE"4V"
CDS_LIB"pure_quanta"
PART_NUMBER"CH622KMEB02";
"B"
$PN"2"2;
"A"
$PN"1"1;
%"UNIVERSAL_GND"
"1","(-6450,2825)","0","pure_quanta_power","I7";
;
CDS_LIB"pure_quanta_power"
HDL_POWER"GND";
"A"12;
%"Q_CAP"
"1","(-1525,4325)","0","pure_quanta","I70";
;
LOCATION"C429"
$SEC"1"
CDS_SEC"1"
VOLTAGE"6.3V"
VALUE"10UF"
MATERIAL"X6S"
TOLERANCE"20%"
PACK_TYPE"C0402"
CDS_LIB"pure_quanta"
PART_NUMBER"CH6101MEB01";
"B"
$PN"2"2;
"A"
$PN"1"1;
%"Q_CAP"
"1","(-1350,3700)","0","pure_quanta","I71";
;
LOCATION"C382"
$SEC"1"
CDS_SEC"1"
TOLERANCE"20%"
PACK_TYPE"0201"
VOLTAGE"4V"
VALUE"1UF"
MATERIAL"X6S"
CDS_LIB"pure_quanta"
PART_NUMBER"CH-10KMEE00";
"B"
$PN"2"2;
"A"
$PN"1"1;
%"Q_CAP"
"1","(-1225,4325)","0","pure_quanta","I72";
;
LOCATION"C431"
$SEC"1"
CDS_SEC"1"
VALUE"10UF"
VOLTAGE"6.3V"
TOLERANCE"20%"
MATERIAL"X6S"
PACK_TYPE"C0402"
CDS_LIB"pure_quanta"
PART_NUMBER"CH6101MEB01";
"B"
$PN"2"2;
"A"
$PN"1"1;
%"UNIVERSAL_GND"
"1","(-825,2650)","0","pure_quanta_power","I73";
;
CDS_LIB"pure_quanta_power"
HDL_POWER"GND";
"A"2;
%"Q_INDUCTOR"
"1","(-3775,4600)","0","pure_quanta","I74";
;
LOCATION"L8"
$SEC"1"
CDS_SEC"1"
MATERIAL"IND"
PACK_TYPE"SMLF"
VALUE"100NH/16A"
CDS_LIB"pure_quanta"
NEEDS_NO_SIZE"TRUE"
PART_NUMBER"CV+10G0MZ04";
"1"
$PN"1"3;
"2"
$PN"2"1;
%"VCC_CORE"
"1","(-3425,4975)","0","pure_quanta_power","I75";
;
HDL_POWER"P0V9_CPU1_RT2_2A"
CDS_LIB"pure_quanta_power";
"A"1;
%"Q_CAP"
"1","(-4100,5625)","0","pure_quanta","I76";
;
LOCATION"C404"
$SEC"1"
CDS_SEC"1"
PACK_TYPE"C0805"
VOLTAGE"4V"
VALUE"100UF"
TOLERANCE"20%"
MATERIAL"X6S"
CDS_LIB"pure_quanta"
PART_NUMBER"CH710KMEA01";
"B"
$PN"2"4;
"A"
$PN"1"3;
%"Q_CAP"
"1","(-3825,5625)","0","pure_quanta","I77";
;
LOCATION"C408"
$SEC"1"
CDS_SEC"1"
VOLTAGE"4V"
TOLERANCE"20%"
VALUE"22UF"
MATERIAL"X6S"
PACK_TYPE"C0402"
CDS_LIB"pure_quanta"
PART_NUMBER"CH622KMEB02";
"B"
$PN"2"4;
"A"
$PN"1"3;
%"Q_CAP"
"1","(-3500,5600)","0","pure_quanta","I78";
;
LOCATION"C414"
$SEC"1"
CDS_SEC"1"
VOLTAGE"6.3V"
VALUE"10UF"
PACK_TYPE"C0402"
MATERIAL"X6S"
TOLERANCE"20%"
CDS_LIB"pure_quanta"
PART_NUMBER"CH6101MEB01";
"B"
$PN"2"4;
"A"
$PN"1"3;
%"Q_CAP"
"1","(-3200,5600)","0","pure_quanta","I79";
;
LOCATION"C419"
$SEC"1"
CDS_SEC"1"
VALUE"4.7UF"
VOLTAGE"6.3V"
TOLERANCE"20%"
MATERIAL"X6S"
PACK_TYPE"0402"
CDS_LIB"pure_quanta"
PART_NUMBER"CH5471MEB01";
"B"
$PN"2"4;
"A"
$PN"1"3;
%"Q_CAP"
"1","(-6450,3225)","0","pure_quanta","I8";
;
LOCATION"C378"
$SEC"1"
CDS_SEC"1"
TOLERANCE"10%"
VALUE"0.1UF"
VOLTAGE"10V"
MATERIAL"X7S"
PACK_TYPE"C0201"
CDS_LIB"pure_quanta"
PART_NUMBER"CH4102K6E00";
"B"
$PN"2"12;
"A"
$PN"1"13;
%"Q_CAP"
"1","(-2900,5600)","0","pure_quanta","I80";
;
LOCATION"C423"
$SEC"1"
CDS_SEC"1"
VALUE"1UF"
VOLTAGE"4V"
TOLERANCE"20%"
PACK_TYPE"0201"
MATERIAL"X6S"
CDS_LIB"pure_quanta"
PART_NUMBER"CH-10KMEE00";
"B"
$PN"2"4;
"A"
$PN"1"3;
%"UNIVERSAL_GND"
"1","(-225,4600)","0","pure_quanta_power","I81";
;
CDS_LIB"pure_quanta_power"
HDL_POWER"GND";
"A"4;
%"Q_CAP"
"1","(-2600,5575)","0","pure_quanta","I82";
;
LOCATION"C383"
$SEC"1"
CDS_SEC"1"
PACK_TYPE"C0201"
VOLTAGE"10V"
VALUE"0.1UF"
MATERIAL"X7S"
TOLERANCE"10%"
CDS_LIB"pure_quanta"
PART_NUMBER"CH4102K6E00";
"B"
$PN"2"4;
"A"
$PN"1"3;
%"Q_CAP"
"1","(-2325,5575)","0","pure_quanta","I83";
;
LOCATION"C385"
$SEC"1"
CDS_SEC"1"
PACK_TYPE"C0201"
MATERIAL"X7S"
VALUE"0.1UF"
VOLTAGE"10V"
TOLERANCE"10%"
CDS_LIB"pure_quanta"
PART_NUMBER"CH4102K6E00";
"B"
$PN"2"4;
"A"
$PN"1"3;
%"Q_CAP"
"1","(-2075,5575)","0","pure_quanta","I84";
;
LOCATION"C388"
$SEC"1"
CDS_SEC"1"
VALUE"0.1UF"
VOLTAGE"10V"
TOLERANCE"10%"
MATERIAL"X7S"
PACK_TYPE"C0201"
CDS_LIB"pure_quanta"
PART_NUMBER"CH4102K6E00";
"B"
$PN"2"4;
"A"
$PN"1"3;
%"Q_CAP"
"1","(-1800,5575)","0","pure_quanta","I85";
;
LOCATION"C392"
$SEC"1"
CDS_SEC"1"
VALUE"0.1UF"
MATERIAL"X7S"
TOLERANCE"10%"
VOLTAGE"10V"
PACK_TYPE"C0201"
CDS_LIB"pure_quanta"
PART_NUMBER"CH4102K6E00";
"B"
$PN"2"4;
"A"
$PN"1"3;
%"Q_CAP"
"1","(-2975,4325)","0","pure_quanta","I86";
;
LOCATION"C405"
$SEC"1"
CDS_SEC"1"
VALUE"100UF"
PACK_TYPE"C0805"
MATERIAL"X6S"
TOLERANCE"20%"
VOLTAGE"4V"
CDS_LIB"pure_quanta"
PART_NUMBER"CH710KMEA01";
"B"
$PN"2"2;
"A"
$PN"1"1;
%"Q_CAP"
"1","(-2750,4325)","0","pure_quanta","I87";
;
LOCATION"C409"
$SEC"1"
CDS_SEC"1"
TOLERANCE"20%"
PACK_TYPE"C0805"
VALUE"100UF"
VOLTAGE"4V"
MATERIAL"X6S"
CDS_LIB"pure_quanta"
PART_NUMBER"CH710KMEA01";
"B"
$PN"2"2;
"A"
$PN"1"1;
%"Q_INDUCTOR"
"1","(-8175,4250)","3","pure_quanta","I88";
;
LOCATION"L32"
$SEC"1"
CDS_SEC"1"
MATERIAL"IND"
PACK_TYPE"SMLF"
VALUE"BLM15PD121SN1D/1300MA"
CDS_LIB"pure_quanta"
NEEDS_NO_SIZE"TRUE"
PART_NUMBER"CX5PD121000";
"1"
$PN"1"7;
"2"
$PN"2"13;
%"Q_RES"
"2","(-8050,4225)","0","pure_quanta","I89";
;
LOCATION"R857"
$SEC"1"
CDS_SEC"1"
VALUE"0"
TOLERANCE"5%"
WATTAGE"1/16W"
PACK_TYPE"0402LF"
MATERIAL"EMPTY"
CDS_LIB"pure_quanta"
PART_NUMBER"CS00002JB13";
"A"
$PN"1"7;
"B"
$PN"2"13;
%"P1V0"
"1","(-6850,3625)","0","pure_quanta_power","I9";
;
HDL_POWER"P1V8_CPU1_RT2_1A_1D"
CDS_LIB"pure_quanta_power";
"A"13;
%"Q_CAP"
"1","(-2975,1275)","0","pure_quanta","I90";
;
LOCATION"C390"
$SEC"1"
CDS_SEC"1"
VOLTAGE"4V"
VALUE"1UF"
TOLERANCE"20%"
MATERIAL"X6S"
PACK_TYPE"0201"
CDS_LIB"pure_quanta"
PART_NUMBER"CH-10KMEE00";
"B"
$PN"2"10;
"A"
$PN"1"9;
%"Q_CAP"
"1","(-2725,1275)","0","pure_quanta","I91";
;
LOCATION"C394"
$SEC"1"
CDS_SEC"1"
PACK_TYPE"0201"
MATERIAL"X6S"
TOLERANCE"20%"
VALUE"1UF"
VOLTAGE"4V"
CDS_LIB"pure_quanta"
PART_NUMBER"CH-10KMEE00";
"B"
$PN"2"10;
"A"
$PN"1"9;
%"Q_CAP"
"1","(-1800,3050)","0","pure_quanta","I92";
;
LOCATION"C426"
$SEC"1"
CDS_SEC"1"
VALUE"0.1UF"
VOLTAGE"10V"
PACK_TYPE"C0201"
MATERIAL"X7S"
TOLERANCE"10%"
CDS_LIB"pure_quanta"
PART_NUMBER"CH4102K6E00";
"B"
$PN"2"2;
"A"
$PN"1"1;
%"Q_CAP"
"1","(-1550,3050)","0","pure_quanta","I93";
;
LOCATION"C428"
$SEC"1"
CDS_SEC"1"
TOLERANCE"10%"
PACK_TYPE"C0201"
MATERIAL"X7S"
VOLTAGE"10V"
VALUE"0.1UF"
CDS_LIB"pure_quanta"
PART_NUMBER"CH4102K6E00";
"B"
$PN"2"2;
"A"
$PN"1"1;
%"Q_CAPP"
"1","(-1500,5600)","0","pure_quanta","I94";
;
LOCATION"C7004"
$SEC"1"
CDS_SEC"1"
VALUE"470UF"
MATERIAL"SPCAP"
TOLERANCE"20%"
VOLTAGE"2.5V"
PACK_TYPE"SMLF"
CDS_LIB"pure_quanta"
PART_NUMBER"CH747LM8818";
"A"
$PN"1"3;
"B"
$PN"2"4;
%"Q_CAPP"
"1","(-1200,5600)","0","pure_quanta","I95";
;
LOCATION"C7005"
$SEC"1"
CDS_SEC"1"
TOLERANCE"20%"
PACK_TYPE"SMLF"
VALUE"470UF"
MATERIAL"SPCAP"
VOLTAGE"2.5V"
CDS_LIB"pure_quanta"
PART_NUMBER"CH747LM8818";
"A"
$PN"1"3;
"B"
$PN"2"4;
%"Q_CAP"
"1","(-900,5600)","0","pure_quanta","I96";
;
LOCATION"C7006"
$SEC"1"
CDS_SEC"1"
TOLERANCE"20%"
PACK_TYPE"C0805"
VALUE"47UF"
MATERIAL"X6S"
VOLTAGE"4V"
CDS_LIB"pure_quanta"
PART_NUMBER"CH647KMEA04";
"B"
$PN"2"4;
"A"
$PN"1"3;
%"Q_CAP"
"1","(-500,5575)","0","pure_quanta","I97";
;
LOCATION"C7007"
$SEC"1"
CDS_SEC"1"
TOLERANCE"20%"
MATERIAL"X6S"
VALUE"47UF"
PACK_TYPE"C0805"
VOLTAGE"4V"
CDS_LIB"pure_quanta"
PART_NUMBER"CH647KMEA04";
"B"
$PN"2"4;
"A"
$PN"1"3;
%"Q_CAPP"
"1","(-1025,2400)","0","pure_quanta","I98";
;
LOCATION"C7026"
$SEC"1"
CDS_SEC"1"
TOLERANCE"20%"
VALUE"470UF"
PACK_TYPE"SMLF"
VOLTAGE"2.5V"
MATERIAL"SPCAP"
CDS_LIB"pure_quanta"
PART_NUMBER"CH747LM8818";
"A"
$PN"1"1;
"B"
$PN"2"11;
%"Q_CAPP"
"1","(-725,2400)","0","pure_quanta","I99";
;
LOCATION"C7027"
$SEC"1"
CDS_SEC"1"
VOLTAGE"2.5V"
PACK_TYPE"SMLF"
MATERIAL"SPCAP"
TOLERANCE"20%"
VALUE"470UF"
CDS_LIB"pure_quanta"
PART_NUMBER"CH747LM8818";
"A"
$PN"1"1;
"B"
$PN"2"11;
END.
